(kicad_pcb
	(version 20221018)
	(generator pcbnew)
	(general
    (thickness 1.562)
  )
	(paper "A4")
	(title_block
    (title "Thunderbolt PCIe Adaper")
    (date "2024-07-09")
    (rev "1.0.3")
    (comment 1 "www.antmicro.com")
    (comment 2 "Antmicro Ltd.")
		(comment 9 "footprints 18-25 of 271")
	)
	(layers
    (0 "F.Cu" signal)
    (1 "In1.Cu" signal)
    (2 "In2.Cu" signal)
    (3 "In3.Cu" signal)
    (4 "In4.Cu" signal)
    (31 "B.Cu" signal)
    (32 "B.Adhes" user "B.Adhesive")
    (33 "F.Adhes" user "F.Adhesive")
    (34 "B.Paste" user)
    (35 "F.Paste" user)
    (36 "B.SilkS" user "B.Silkscreen")
    (37 "F.SilkS" user "F.Silkscreen")
    (38 "B.Mask" user)
    (39 "F.Mask" user)
    (40 "Dwgs.User" user "User.Drawings")
    (41 "Cmts.User" user "User.Comments")
    (42 "Eco1.User" user "User.Eco1")
    (43 "Eco2.User" user "User.Eco2")
    (44 "Edge.Cuts" user)
    (45 "Margin" user)
    (46 "B.CrtYd" user "B.Courtyard")
    (47 "F.CrtYd" user "F.Courtyard")
    (48 "B.Fab" user)
    (49 "F.Fab" user)
  )
	(footprint "antmicro-footprints:TP_SMD_1mm" (layer "F.Cu")
    (at 118.53 86.38)
    (property "Author" "Antmicro")
    (property "License" "Apache-2.0")
    (property "MPN" "")
    (property "Manufacturer" "")
    (property "Sheetfile" "power.kicad_sch")
    (property "Sheetname" "Power")
    (property "exclude_from_bom" "")
    (property "ki_description" "Test point 1mm SMD")
    (property "ki_keywords" "TESTPOINT")
    (attr exclude_from_pos_files exclude_from_bom)
    (fp_text reference "TP8" (at -1.055 -0.731898) (layer "F.SilkS")
        (effects (font (size 0.7 0.7) (thickness 0.15)) (justify left bottom))
    )
    (fp_text value "TP_1mm_SMD" (at 0 1.4) (layer "F.Fab")
        (effects (font (size 0.7 0.7) (thickness 0.15)) (justify left bottom))
    )
    (fp_text user "Author: Antmicro" (at -0.5 4) (layer "F.Fab") hide
        (effects (font (size 0.7 0.7) (thickness 0.15)) (justify left bottom))
    )
    (fp_text user "License: Apache-2.0" (at -0.5 5.2) (layer "F.Fab") hide
        (effects (font (size 0.7 0.7) (thickness 0.15)) (justify left bottom))
    )
    (fp_text user "${REFERENCE}" (at -0.5 2.8) (layer "F.Fab") hide
        (effects (font (size 0.7 0.7) (thickness 0.15)) (justify left bottom))
    )
    (fp_circle (center 0 0) (end 0.6 0)
      (stroke (width 0.05) (type default)) (fill none) (layer "F.CrtYd"))
    (pad "1" smd circle (at 0 0) (size 1 1) (layers "F.Cu" "F.Mask")
      (net 60 "12V0_DCDC") (pinfunction "1") (pintype "passive"))
  )
	(footprint "antmicro-footprints:C_0603_1608Metric" (layer "F.Cu")
    (at 118.560002 79.9 -90)
    (descr "Capacitor SMD 0603")
    (tags "capacitor 0603")
    (property "Author" "Antmicro")
    (property "Dielectric" "")
    (property "License" "Apache-2.0")
    (property "MPN" "CL10A226MO7JZNC")
    (property "Manufacturer" "Samsung Electro-Mechanics")
    (property "Sheetfile" "power.kicad_sch")
    (property "Sheetname" "Power")
    (property "Val" "22u")
    (property "Voltage" "16V")
    (property "ki_description" "SMD Multilayer Ceramic Capacitor")
    (property "ki_keywords" "0603, SMT, CAPACITOR, PASSIVE, CERAMIC")
    (attr smd)
    (fp_text reference "C40" (at -1.16 -0.340998 -90) (layer "F.SilkS")
        (effects (font (size 0.7 0.7) (thickness 0.15)) (justify left bottom))
    )
    (fp_text value "C_22u_16V_0603" (at -1.42757 1.770288 -90) (layer "F.Fab")
        (effects (font (size 0.7 0.7) (thickness 0.15)) (justify left bottom))
    )
    (fp_text user "Author: Antmicro" (at -1.682 4.894 -90) (layer "F.Fab") hide
        (effects (font (size 0.7 0.7) (thickness 0.15)) (justify left bottom))
    )
    (fp_text user "License: Apache-2.0" (at -1.682 5.895 -90) (layer "F.Fab") hide
        (effects (font (size 0.7 0.7) (thickness 0.15)) (justify left bottom))
    )
    (fp_text user "${REFERENCE}" (at -1.682 3.895 -90) (layer "F.Fab") hide
        (effects (font (size 0.7 0.7) (thickness 0.15)) (justify left bottom))
    )
    (fp_line (start -0.15 -0.4) (end 0.15 -0.4)
      (stroke (width 0.15) (type solid)) (layer "F.SilkS"))
    (fp_line (start -0.15 0.4) (end 0.15 0.4)
      (stroke (width 0.15) (type solid)) (layer "F.SilkS"))
    (fp_rect (start -1.25 -0.65) (end 1.25 0.65)
      (stroke (width 0.05) (type solid)) (fill none) (layer "F.CrtYd"))
    (fp_rect (start -0.8 -0.4) (end 0.8 0.4)
      (stroke (width 0.15) (type solid)) (fill none) (layer "F.Fab"))
    (pad "1" smd roundrect (at -0.7 0 270) (size 0.8 1) (layers "F.Cu" "F.Paste" "F.Mask") (roundrect_rratio 0.2)
      (net 1 "GND") (pintype "passive"))
    (pad "2" smd roundrect (at 0.7 0 270) (size 0.8 1) (layers "F.Cu" "F.Paste" "F.Mask") (roundrect_rratio 0.2)
      (net 75 "Net-(C32-Pad2)") (pintype "passive"))
  )
	(footprint "antmicro-footprints:C_0805_2012Metric" (layer "F.Cu")
    (at 103.055 78.0825 -90)
    (descr "Capacitor SMD 0805")
    (tags "capacitor SMD 0805")
    (property "Author" "Antmicro")
    (property "Dielectric" "")
    (property "License" "Apache-2.0")
    (property "MPN" "GRM21BR6YA106KE43L")
    (property "Manufacturer" "Murata")
    (property "Sheetfile" "power.kicad_sch")
    (property "Sheetname" "Power")
    (property "Val" "10u")
    (property "Voltage" "35V")
    (property "ki_description" "SMD Multilayer Ceramic Capacitor, 10 µF, 35 V, 0805 [2012 Metric], ± 10%, X5R, GRM Series")
    (property "ki_keywords" "0805, SMT, CAPACITOR, PASSIVE")
    (attr smd)
    (fp_text reference "C12" (at 1.1655 1.074 -90) (layer "F.SilkS")
        (effects (font (size 0.7 0.7) (thickness 0.15)) (justify left bottom))
    )
    (fp_text value "C_10u_0805_35V" (at -2.055717 1.963152 -90) (layer "F.Fab")
        (effects (font (size 0.7 0.7) (thickness 0.15)) (justify left bottom))
    )
    (fp_text user "${REFERENCE}" (at -1.9 3.947 -90) (layer "F.Fab") hide
        (effects (font (size 0.7 0.7) (thickness 0.15)) (justify left bottom))
    )
    (fp_text user "Author: Antmicro" (at -1.9 5.947 -90) (layer "F.Fab") hide
        (effects (font (size 0.7 0.7) (thickness 0.15)) (justify left bottom))
    )
    (fp_text user "License: Apache-2.0" (at -1.9 4.947 -90) (layer "F.Fab") hide
        (effects (font (size 0.7 0.7) (thickness 0.15)) (justify left bottom))
    )
    (fp_line (start -0.3 -0.7) (end 0.3 -0.7)
      (stroke (width 0.15) (type solid)) (layer "F.SilkS"))
    (fp_line (start -0.3 0.7) (end 0.3 0.7)
      (stroke (width 0.15) (type solid)) (layer "F.SilkS"))
    (fp_rect (start 1.95 -0.9) (end -1.95 0.9)
      (stroke (width 0.05) (type default)) (fill none) (layer "F.CrtYd"))
    (fp_rect (start -0.95 -0.675) (end 0.95 0.675)
      (stroke (width 0.15) (type solid)) (fill none) (layer "F.Fab"))
    (pad "1" smd roundrect (at -1.1 0 270) (size 1.2 1.3) (layers "F.Cu" "F.Paste" "F.Mask") (roundrect_rratio 0.25)
      (net 1 "GND") (pintype "passive"))
    (pad "2" smd roundrect (at 1.1 0 270) (size 1.2 1.3) (layers "F.Cu" "F.Paste" "F.Mask") (roundrect_rratio 0.25)
      (net 74 "Net-(C10-Pad2)") (pintype "passive"))
  )
	(footprint "antmicro-footprints:C_0805_2012Metric" (layer "F.Cu")
    (at 105.991001 65.219 90)
    (descr "Capacitor SMD 0805")
    (tags "capacitor SMD 0805")
    (property "Author" "Antmicro")
    (property "Dielectric" "")
    (property "License" "Apache-2.0")
    (property "MPN" "GRM21BR6YA106KE43L")
    (property "Manufacturer" "Murata")
    (property "Sheetfile" "power.kicad_sch")
    (property "Sheetname" "Power")
    (property "Val" "10u")
    (property "Voltage" "35V")
    (property "ki_description" "SMD Multilayer Ceramic Capacitor, 10 µF, 35 V, 0805 [2012 Metric], ± 10%, X5R, GRM Series")
    (property "ki_keywords" "0805, SMT, CAPACITOR, PASSIVE")
    (attr smd)
    (fp_text reference "C9" (at -0.694 -1.089001 90) (layer "F.SilkS")
        (effects (font (size 0.7 0.7) (thickness 0.15)) (justify left bottom))
    )
    (fp_text value "C_10u_0805_35V" (at -2.055717 1.963152 90) (layer "F.Fab")
        (effects (font (size 0.7 0.7) (thickness 0.15)) (justify left bottom))
    )
    (fp_text user "${REFERENCE}" (at -1.9 3.947 90) (layer "F.Fab") hide
        (effects (font (size 0.7 0.7) (thickness 0.15)) (justify left bottom))
    )
    (fp_text user "License: Apache-2.0" (at -1.9 4.947 90) (layer "F.Fab") hide
        (effects (font (size 0.7 0.7) (thickness 0.15)) (justify left bottom))
    )
    (fp_text user "Author: Antmicro" (at -1.9 5.947 90) (layer "F.Fab") hide
        (effects (font (size 0.7 0.7) (thickness 0.15)) (justify left bottom))
    )
    (fp_line (start -0.3 -0.7) (end 0.3 -0.7)
      (stroke (width 0.15) (type solid)) (layer "F.SilkS"))
    (fp_line (start -0.3 0.7) (end 0.3 0.7)
      (stroke (width 0.15) (type solid)) (layer "F.SilkS"))
    (fp_rect (start 1.95 -0.9) (end -1.95 0.9)
      (stroke (width 0.05) (type default)) (fill none) (layer "F.CrtYd"))
    (fp_rect (start -0.95 -0.675) (end 0.95 0.675)
      (stroke (width 0.15) (type solid)) (fill none) (layer "F.Fab"))
    (pad "1" smd roundrect (at -1.1 0 90) (size 1.2 1.3) (layers "F.Cu" "F.Paste" "F.Mask") (roundrect_rratio 0.25)
      (net 1 "GND") (pintype "passive"))
    (pad "2" smd roundrect (at 1.1 0 90) (size 1.2 1.3) (layers "F.Cu" "F.Paste" "F.Mask") (roundrect_rratio 0.25)
      (net 3 "5V0_USB") (pintype "passive"))
  )
	(footprint "antmicro-footprints:Conn_Molex_Nano-Fit_1x2_1053131102" (layer "F.Cu")
    (at 160.01 88.55 90)
    (property "Author" "Antmicro")
    (property "License" "Apache-2.0")
    (property "MPN" "1053131102")
    (property "Manufacturer" "Molex")
    (property "Sheetfile" "connectors.kicad_sch")
    (property "Sheetname" "Connectors")
    (property "ki_description" "Rectangular connector, header")
    (property "ki_keywords" "CONNECTOR, THT")
    (attr through_hole)
    (fp_text reference "J3" (at 2.444 4.328 180) (layer "F.SilkS")
        (effects (font (size 0.7 0.7) (thickness 0.15)) (justify left bottom))
    )
    (fp_text value "Molex_Nano-Fit_1x2_1053131102" (at 0 13.1 90) (layer "F.Fab")
        (effects (font (size 0.7 0.7) (thickness 0.15)) (justify left bottom))
    )
    (fp_text user "${REFERENCE}" (at -4.221 14.55 90) (layer "F.Fab") hide
        (effects (font (size 0.7 0.7) (thickness 0.15)) (justify left bottom))
    )
    (fp_text user "Author: Antmicro" (at -4.221 15.749 90) (layer "F.Fab") hide
        (effects (font (size 0.7 0.7) (thickness 0.15)) (justify left bottom))
    )
    (fp_text user "License: Apache-2.0" (at -4.221 16.949 90) (layer "F.Fab") hide
        (effects (font (size 0.7 0.7) (thickness 0.15)) (justify left bottom))
    )
    (fp_line (start -4.221 1.918) (end -4.221 10.38)
      (stroke (width 0.15) (type solid)) (layer "F.SilkS"))
    (fp_line (start -4.221 1.918) (end 1.719 1.918)
      (stroke (width 0.15) (type solid)) (layer "F.SilkS"))
    (fp_line (start -4.221 10.38) (end 1.719 10.38)
      (stroke (width 0.15) (type solid)) (layer "F.SilkS"))
    (fp_line (start 0.998 1.199) (end 1.699 1.199)
      (stroke (width 0.15) (type solid)) (layer "F.SilkS"))
    (fp_line (start 1.35 1.55) (end 1.35 0.848)
      (stroke (width 0.15) (type solid)) (layer "F.SilkS"))
    (fp_line (start 1.719 1.918) (end 1.719 10.38)
      (stroke (width 0.15) (type solid)) (layer "F.SilkS"))
    (fp_rect (start -4.721 -1.1) (end 2.219 12.1)
      (stroke (width 0.05) (type solid)) (fill none) (layer "F.CrtYd"))
    (pad "" np_thru_hole circle (at -2.5 7.179 90) (size 1.71 1.71) (drill 1.7) (layers "*.Cu" "*.Mask"))
    (pad "" np_thru_hole circle (at 0 7.179 90) (size 1.71 1.71) (drill 1.7) (layers "*.Cu" "*.Mask"))
    (pad "1" thru_hole circle (at 0 0 90) (size 2 2) (drill 1.3) (layers "*.Cu" "*.Mask")
      (net 61 "12V0_MOLEX") (pintype "input"))
    (pad "2" thru_hole circle (at -2.5 0 90) (size 2 2) (drill 1.3) (layers "*.Cu" "*.Mask")
      (net 1 "GND") (pintype "input"))
  )
	(footprint "antmicro-footprints:C_0603_1608Metric" (layer "F.Cu")
    (at 115.610002 79.9 -90)
    (descr "Capacitor SMD 0603")
    (tags "capacitor 0603")
    (property "Author" "Antmicro")
    (property "Dielectric" "")
    (property "License" "Apache-2.0")
    (property "MPN" "CL10A226MO7JZNC")
    (property "Manufacturer" "Samsung Electro-Mechanics")
    (property "Sheetfile" "power.kicad_sch")
    (property "Sheetname" "Power")
    (property "Val" "22u")
    (property "Voltage" "16V")
    (property "ki_description" "SMD Multilayer Ceramic Capacitor")
    (property "ki_keywords" "0603, SMT, CAPACITOR, PASSIVE, CERAMIC")
    (attr smd)
    (fp_text reference "C43" (at -1.16 -0.340998 -90) (layer "F.SilkS")
        (effects (font (size 0.7 0.7) (thickness 0.15)) (justify left bottom))
    )
    (fp_text value "C_22u_16V_0603" (at -1.42757 1.770288 -90) (layer "F.Fab")
        (effects (font (size 0.7 0.7) (thickness 0.15)) (justify left bottom))
    )
    (fp_text user "${REFERENCE}" (at -1.682 3.895 -90) (layer "F.Fab") hide
        (effects (font (size 0.7 0.7) (thickness 0.15)) (justify left bottom))
    )
    (fp_text user "Author: Antmicro" (at -1.682 4.894 -90) (layer "F.Fab") hide
        (effects (font (size 0.7 0.7) (thickness 0.15)) (justify left bottom))
    )
    (fp_text user "License: Apache-2.0" (at -1.682 5.895 -90) (layer "F.Fab") hide
        (effects (font (size 0.7 0.7) (thickness 0.15)) (justify left bottom))
    )
    (fp_line (start -0.15 -0.4) (end 0.15 -0.4)
      (stroke (width 0.15) (type solid)) (layer "F.SilkS"))
    (fp_line (start -0.15 0.4) (end 0.15 0.4)
      (stroke (width 0.15) (type solid)) (layer "F.SilkS"))
    (fp_rect (start -1.25 -0.65) (end 1.25 0.65)
      (stroke (width 0.05) (type solid)) (fill none) (layer "F.CrtYd"))
    (fp_rect (start -0.8 -0.4) (end 0.8 0.4)
      (stroke (width 0.15) (type solid)) (fill none) (layer "F.Fab"))
    (pad "1" smd roundrect (at -0.7 0 270) (size 0.8 1) (layers "F.Cu" "F.Paste" "F.Mask") (roundrect_rratio 0.2)
      (net 1 "GND") (pintype "passive"))
    (pad "2" smd roundrect (at 0.7 0 270) (size 0.8 1) (layers "F.Cu" "F.Paste" "F.Mask") (roundrect_rratio 0.2)
      (net 75 "Net-(C32-Pad2)") (pintype "passive"))
  )
	(footprint "antmicro-footprints:LED_0603_1608Metric_G" (layer "F.Cu")
    (at 147.5 68.74 180)
    (descr "LED SMD 0603 Green")
    (tags "LED SMD 0603 Green")
    (property "Author" "Antmicro")
    (property "Color" "Green")
    (property "License" "Apache-2.0")
    (property "MPN" "KP-1608CGCK")
    (property "Manufacturer" "Kingbright")
    (property "Sheetfile" "tb-power.kicad_sch")
    (property "Sheetname" "Thunderbolt Controller - Power")
    (property "ki_description" "LED, Green, SMD, 0603, 20 mA, 2.1 V, 570 nm")
    (property "ki_keywords" "SMT, DIODE, SEMICONDUCTOR, LED")
    (attr smd)
    (fp_text reference "D4" (at -1.344 -0.475 180) (layer "F.SilkS")
        (effects (font (size 0.7 0.7) (thickness 0.15)) (justify left bottom))
    )
    (fp_text value "LED_G_0603_KP-1608CGCK" (at -0.001 1.599 180) (layer "F.Fab")
        (effects (font (size 0.7 0.7) (thickness 0.15)) (justify left bottom))
    )
    (fp_text user "${REFERENCE}" (at -1.4224 5.999 180) (layer "F.Fab") hide
        (effects (font (size 0.7 0.7) (thickness 0.15)) (justify left bottom))
    )
    (fp_text user "License: Apache-2.0" (at -1.4224 3.599 180) (layer "F.Fab") hide
        (effects (font (size 0.7 0.7) (thickness 0.15)) (justify left bottom))
    )
    (fp_text user "Author: Antmicro" (at -1.4224 4.799 180) (layer "F.Fab") hide
        (effects (font (size 0.7 0.7) (thickness 0.15)) (justify left bottom))
    )
    (fp_line (start -1.18 -0.319) (end -1.18 0.321)
      (stroke (width 0.15) (type solid)) (layer "F.SilkS"))
    (fp_line (start -0.094672 0.001008) (end -0.24 0.001008)
      (stroke (width 0.1) (type solid)) (layer "F.SilkS"))
    (fp_line (start -0.094672 0.001008) (end 0.105328 -0.198992)
      (stroke (width 0.1) (type solid)) (layer "F.SilkS"))
    (fp_line (start -0.094672 0.201008) (end -0.094672 -0.198992)
      (stroke (width 0.1) (type solid)) (layer "F.SilkS"))
    (fp_line (start 0.105328 0.001008) (end 0.24 0.001)
      (stroke (width 0.1) (type solid)) (layer "F.SilkS"))
    (fp_line (start 0.105328 0.201008) (end -0.094672 0.001008)
      (stroke (width 0.1) (type solid)) (layer "F.SilkS"))
    (fp_line (start 0.105328 0.201008) (end 0.105328 -0.198992)
      (stroke (width 0.1) (type solid)) (layer "F.SilkS"))
    (fp_line (start 0.22 -0.35) (end -0.22 -0.35)
      (stroke (width 0.15) (type solid)) (layer "F.SilkS"))
    (fp_line (start 0.22 0.35) (end -0.22 0.35)
      (stroke (width 0.15) (type solid)) (layer "F.SilkS"))
    (fp_rect (start 1.25 0.65) (end -1.25 -0.65)
      (stroke (width 0.05) (type solid)) (fill none) (layer "F.CrtYd"))
    (fp_line (start -0.199 -0.202) (end -0.199 0.1)
      (stroke (width 0.15) (type solid)) (layer "F.Fab"))
    (fp_line (start -0.199 0) (end -0.597 0)
      (stroke (width 0.15) (type solid)) (layer "F.Fab"))
    (fp_line (start -0.199 0.2) (end -0.199 0.1)
      (stroke (width 0.15) (type solid)) (layer "F.Fab"))
    (fp_line (start -0.101 0) (end 0.201 0.2)
      (stroke (width 0.15) (type solid)) (layer "F.Fab"))
    (fp_line (start 0.201 -0.202) (end -0.101 0)
      (stroke (width 0.15) (type solid)) (layer "F.Fab"))
    (fp_line (start 0.201 0) (end 0.201 -0.202)
      (stroke (width 0.15) (type solid)) (layer "F.Fab"))
    (fp_line (start 0.201 0.2) (end 0.201 0)
      (stroke (width 0.15) (type solid)) (layer "F.Fab"))
    (fp_line (start 0.599 0) (end 0.201 0)
      (stroke (width 0.15) (type solid)) (layer "F.Fab"))
    (fp_rect (start 0.848 0.4) (end -0.85 -0.402)
      (stroke (width 0.15) (type solid)) (fill none) (layer "F.Fab"))
    (pad "1" smd roundrect (at -0.7 0) (size 0.8 1) (layers "F.Cu" "F.Paste" "F.Mask") (roundrect_rratio 0.2)
      (net 122 "Net-(D4-C)") (pinfunction "C") (pintype "passive"))
    (pad "2" smd roundrect (at 0.7 0) (size 0.8 1) (layers "F.Cu" "F.Paste" "F.Mask") (roundrect_rratio 0.2)
      (net 2 "3V3_SYS") (pinfunction "A") (pintype "passive"))
  )
	(footprint "antmicro-footprints:TP_SMD_0.75mm" (layer "F.Cu")
    (at 113.7 82.9)
    (property "Author" "Antmicro")
    (property "License" "Apache-2.0")
    (property "MPN" "")
    (property "Manufacturer" "")
    (property "Sheetfile" "power.kicad_sch")
    (property "Sheetname" "Power")
    (property "exclude_from_bom" "")
    (property "ki_description" "SMT test point")
    (property "ki_keywords" "TESTPOINT")
    (attr exclude_from_pos_files exclude_from_bom)
    (fp_text reference "TP6" (at 0.6 0.539) (layer "F.SilkS")
        (effects (font (size 0.7 0.7) (thickness 0.15)) (justify left bottom))
    )
    (fp_text value "TP_0.75mm_SMD" (at 0 1.2) (layer "F.Fab")
        (effects (font (size 0.7 0.7) (thickness 0.15)) (justify left bottom))
    )
    (fp_text user "Author: Antmicro" (at -0.4 3.901) (layer "F.Fab") hide
        (effects (font (size 0.7 0.7) (thickness 0.15)) (justify left bottom))
    )
    (fp_text user "License: Apache-2.0" (at -0.4 5.101) (layer "F.Fab") hide
        (effects (font (size 0.7 0.7) (thickness 0.15)) (justify left bottom))
    )
    (fp_text user "${REFERENCE}" (at -0.4 2.7) (layer "F.Fab") hide
        (effects (font (size 0.7 0.7) (thickness 0.15)) (justify left bottom))
    )
    (fp_circle (center 0 0) (end 0.475 0)
      (stroke (width 0.05) (type default)) (fill none) (layer "F.CrtYd"))
    (pad "1" smd circle (at 0 0) (size 0.75 0.75) (layers "F.Cu" "F.Mask")
      (net 207 "Net-(U1-CLKOUT)") (pinfunction "1") (pintype "passive"))
  )
)
